FILE_TYPE = CONNECTIVITY;
{Allegro Design Entry HDL 16.6-p007 (v16-6-112F) 10/10/2012}
"PAGE_NUMBER" = 144;
0"NC";
1"GND\g";
2"GND\g";
3"GND\g";
4"GND\g";
5"SMB_SENSOR_BMC_STBY_LVC3_SDA";
6"BMC_VGA_GREEN";
7"BMC_VGA_BLUE";
8"FM_CPU0_FIVR_FAULT_LVT3_N";
9"SMB_OCP_LAN_STBY_LVC3_SCL_R";
10"SMB_SLOTX24_STBY_LVC3_SDA_R"CDS_PHYS_NET_NAME"SMB_SLOTX24_STBY_LVC3_SDA_R";
11"BMC_DEBUG_EN_N";
12"FM_MP_PS_FAIL_N"PHYS_NET_NAME"H_CPU0_FAST_WAKE_LVT3_N"CDS_PHYS_NET_NAME"H_CPU0_FAST_WAKE_LVT3_N";
13"SMB_SLOTX24_STBY_LVC3_SCL_R"CDS_PHYS_NET_NAME"SMB_SLOTX24_STBY_LVC3_SCL_R";
14"SMB_LAN_STBY_LVC3_SCL_R"PHYS_NET_NAME"H_CPU0_FAST_WAKE_LVT3_N"CDS_PHYS_NET_NAME"H_CPU0_FAST_WAKE_LVT3_N";
15"SMB_LAN_STBY_LVC3_SDA_R"PHYS_NET_NAME"H_CPU0_FAST_WAKE_LVT3_N"CDS_PHYS_NET_NAME"H_CPU0_FAST_WAKE_LVT3_N";
16"H_CPU0_FAST_WAKE_LVT3_N"PHYS_NET_NAME"H_CPU0_FAST_WAKE_LVT3_N"CDS_PHYS_NET_NAME"H_CPU0_FAST_WAKE_LVT3_N";
17"IRQ_BMC_PCH_SMI_LPC_N";
18"PWRGD_SYS_PWROK";
19"CLK_48M_USB_BMC_R";
20"XDP_SYSPWROK";
21"PWRGD_PCH_PWROK"PHYS_NET_NAME"H_CPU0_FAST_WAKE_LVT3_N"CDS_PHYS_NET_NAME"H_CPU0_FAST_WAKE_LVT3_N";
22"IRQ_PVDDQ_GHJ_VRHOT_LVT3_N";
23"CLK_48M_USB_BMC";
24"A_DACRSET";
25"SGPIO_BMC_DOUT_R";
26"FM_PCH_BMC_THERMTRIP_N";
27"FM_CPU0_SKTOCC_LVT3_N";
28"SPI_BMC_CS0_N";
29"SPI_BMC_DI";
30"SGPIO_BMC_CLK_R";
31"SGPIO_BMC_DIN";
32"SGPIO_BMC_DOUT";
33"SGPIO_BMC_LD_N";
34"BMC_VGA_RED";
35"PU_JTAG_BMC_RTCK";
36"BMC_VGA_BLUE";
37"BMC_VGA_RED";
38"SGPIO_BMC_LD_R_N";
39"SGPIO_BMC_CLK";
40"FM_CPU_CATERR_LVT3_N";
41"FM_CPU_ERR2_LVT3_N";
42"JTAG_BMC_TRST_N";
43"JTAG_BMC_TCK";
44"JTAG_BMC_TMS";
45"JTAG_BMC_TDI";
46"JTAG_BMC_TDO";
47"FM_UARTSW_MSB_N";
48"FM_UARTSW_LSB_N";
49"SMB_OCP_LAN_STBY_LVC3_SDA_R";
50"SMB_HOST_STBY_LVC3_SCL_R";
51"SMB_SMLINK0_STBY_LVC3_SCL_R";
52"SMB_SMLINK0_STBY_LVC3_SDA_R";
53"SMB_VR_STBY_LVC3_SCL_R";
54"SMB_VR_STBY_LVC3_SDA_R";
55"SMB_SENSOR_BMC_STBY_LVC3_SCL";
56"SMB_OCP_FRU_STBY_LVC3_SCL_R";
57"SMB_BMC_PMBUS_STBY_LVC3_SDA_R";
58"SMB_BMC_PMBUS_STBY_LVC3_SCL_R";
59"BMC_VGA_GREEN";
60"FM_CPU1_FIVR_FAULT_LVT3_N";
61"SPI_BMC_CLK";
62"SPI_BMC_DO"CDS_PHYS_NET_NAME"SPI_BMC_DO";
63"FM_UV_ADR_TRIGGER_EN"CDS_PHYS_NET_NAME"FM_UV_ADR_TRIGGER_EN";
64"SMB_HOST_STBY_LVC3_SDA_R";
65"SMB_OCP_FRU_STBY_LVC3_SDA_R";
66"FM_FORCE_ADR_N"CDS_PHYS_NET_NAME"FM_FORCE_ADR_N"$PHYS_NET_NAME"FM_FORCE_ADR_N";
67"FM_CPU1_FIVR_FAULT_LVT3_R_N";
68"FM_CPU0_FIVR_FAULT_LVT3_R_N";
%"RES"
"1","(-1750,-2800)","0","mstr_discrete","I114";
;
MATERIAL"CHIP"
PACK_TYPE"0402"
LOCATION"R25W70"
VALUE"33.2"
WATTAGE"1/16W"
PART_NUMBER"G21796-074"
TOLERANCE"1%"
CDS_LOCATION"R25W70"
CDS_LIB"mstr_discrete"
ROOM"BMC"
BOM_COST"SM_CONTROLLER"
SEC_TYPE"0402"
SEC"1"
CDS_SEC"1";
"B"
$PN"2"8;
"A"
$PN"1"68;
%"RES"
"1","(-1750,-2750)","0","mstr_discrete","I118";
;
MATERIAL"CHIP"
TOLERANCE"1%"
WATTAGE"1/16W"
PART_NUMBER"G21796-074"
LOCATION"R25W75"
VALUE"33.2"
PACK_TYPE"0402"
CDS_SEC"1"
SEC"1"
SEC_TYPE"0402"
BOM_COST"SM_CONTROLLER"
ROOM"BMC"
CDS_LIB"mstr_discrete"
CDS_LOCATION"R25W75";
"B"
$PN"2"60;
"A"
$PN"1"67;
%"RES"
"2","(-2800,-4550)","2","mstr_discrete","I139";
;
CDS_SEC"1"
PART_NUMBER"G21796-009"
PACK_TYPE"0402"
MATERIAL"CHIP"
LOCATION"R25W123"
VALUE"150.0"
TOLERANCE"1%"
WATTAGE"1/16W"
GROUP"AST2500"
CDS_LOCATION"R25W123"
SEC_TYPE"0402"
BOM_COST"PROC_SIDEBAND"
CDS_LIB"mstr_discrete"
SEC"1"
ROOM"PROC_SIDEBAND";
"A"
$PN"1"7;
"B"
$PN"2"1;
%"RES"
"2","(-2450,-4550)","2","mstr_discrete","I140";
;
CDS_SEC"1"
CDS_LOCATION"R25W124"
PART_NUMBER"G21796-009"
VALUE"150.0"
MATERIAL"CHIP"
LOCATION"R25W124"
TOLERANCE"1%"
PACK_TYPE"0402"
WATTAGE"1/16W"
GROUP"AST2500"
SEC"1"
SEC_TYPE"0402"
CDS_LIB"mstr_discrete"
BOM_COST"PROC_SIDEBAND"
ROOM"PROC_SIDEBAND";
"A"
$PN"1"59;
"B"
$PN"2"2;
%"RES"
"2","(-2100,-4550)","2","mstr_discrete","I141";
;
CDS_SEC"1"
CDS_LOCATION"R25W125"
PART_NUMBER"G21796-009"
VALUE"150.0"
LOCATION"R25W125"
MATERIAL"CHIP"
TOLERANCE"1%"
PACK_TYPE"0402"
GROUP"AST2500"
WATTAGE"1/16W"
SEC"1"
SEC_TYPE"0402"
CDS_LIB"mstr_discrete"
BOM_COST"PROC_SIDEBAND"
ROOM"PROC_SIDEBAND";
"A"
$PN"1"34;
"B"
$PN"2"3;
%"GND"
"1","(-2800,-4800)","0","mstr_symbols","I142";
;
HDL_POWER"GND"
BODY_TYPE"PLUMBING"
SIZE"1B"
VOLTAGE"0.0V"
CDS_LIB"mstr_symbols";
"A\NAC"1;
%"GND"
"1","(-2450,-4800)","0","mstr_symbols","I143";
;
CDS_LIB"mstr_symbols"
HDL_POWER"GND"
BODY_TYPE"PLUMBING"
SIZE"1B"
VOLTAGE"0.0V";
"A\NAC"2;
%"GND"
"1","(-2100,-4800)","0","mstr_symbols","I144";
;
CDS_LIB"mstr_symbols"
HDL_POWER"GND"
BODY_TYPE"PLUMBING"
SIZE"1B"
VOLTAGE"0.0V";
"A\NAC"3;
%"RES"
"1","(-6700,-4300)","0","mstr_discrete","I148";
;
CDS_SEC"1"
PACK_TYPE"0402"
TOLERANCE"5%"
MATERIAL"EMPTY"
WATTAGE"1/16W"
VALUE"0.0"
LOCATION"R25W140"
PART_NUMBER"G21497-005"
CDS_LIB"mstr_discrete"
ROOM"NV_DIMM"
BOM_COST"MEM_NV"
SEC_TYPE"0402"
SEC"1"
CDS_LOCATION"R25W140";
"B"
$PN"2"19;
"A"
$PN"1"23;
%"18KR2F-GP"
"1","(-2400,-3525)","0","w_hdl","I150";
;
CDS_SEC"1"
CDS_LOCATION"R25W58"
PACK_SIZE"0402"
RATED"1/16W"
TOLERANCE"1%"
VALUE"18KR2F-GP"
LOCATION"R25W58"
ATTRIBUTE"18KOHM"
CDS_LMAN_SYM_OUTLINE"-50,75,50,-75"
CDS_LIB"w_hdl"
PART_NUMBER"64.18025.6DL"
SEC_TYPE"RCL_GP"
SEC"1"
PACK_TYPE"RCL_GP";
"2"
$PN"2"4;
"1"
$PN"1"24;
%"RES"
"1","(-6700,-4050)","0","mstr_discrete","I151";
;
LOCATION"R25W182"
PACK_TYPE"0402"
TOLERANCE"5%"
WATTAGE"1/16W"
VALUE"0.0"
PART_NUMBER"G21497-005"
MATERIAL"CHIP"
POP"NOPOP"
CDS_SEC"1"
SEC"1"
SEC_TYPE"0402"
ROOM"DEBUG"
CDS_LIB"mstr_discrete"
CDS_LOCATION"R25W182";
"B"
$PN"2"18;
"A"
$PN"1"20;
%"RES"
"1","(-1750,-2200)","0","mstr_discrete","I57";
;
CDS_SEC"1"
PART_NUMBER"G21497-048"
LOCATION"R1U14"
TOLERANCE"5.0%"
VALUE"51"
WATTAGE"1/16W"
MATERIAL"CHIP"
PACK_TYPE"0402"
CDS_LOCATION"R1U14"
CDS_LIB"mstr_discrete"
ROOM"BMC"
SEC_TYPE"0402"
SEC"1";
"B"
$PN"2"39;
"A"
$PN"1"30;
%"RES"
"1","(-1750,-2050)","0","mstr_discrete","I58";
;
CDS_SEC"1"
PACK_TYPE"0402"
MATERIAL"CHIP"
PART_NUMBER"G21497-048"
TOLERANCE"5.0%"
LOCATION"R1U13"
VALUE"51"
WATTAGE"1/16W"
CDS_LOCATION"R1U13"
CDS_LIB"mstr_discrete"
ROOM"BMC"
SEC_TYPE"0402"
SEC"1";
"B"
$PN"2"32;
"A"
$PN"1"25;
%"RES"
"1","(-1750,-2150)","0","mstr_discrete","I59";
;
CDS_SEC"1"
MATERIAL"CHIP"
PART_NUMBER"G21497-048"
LOCATION"R1U12"
TOLERANCE"5.0%"
VALUE"51"
WATTAGE"1/16W"
PACK_TYPE"0402"
SEC"1"
CDS_LOCATION"R1U12"
CDS_LIB"mstr_discrete"
ROOM"BMC"
SEC_TYPE"0402";
"B"
$PN"2"33;
"A"
$PN"1"38;
%"GND"
"1","(-2400,-3750)","0","mstr_symbols","I72";
;
CDS_LIB"mstr_symbols"
VOLTAGE"0.0V"
SIZE"1B"
BODY_TYPE"PLUMBING"
HDL_POWER"GND";
"A\NAC"4;
%"AST2520A1-GP-GP"
"2","(-4800,-2600)","0","w_hdl","I95";
;
CDS_SEC"2"
$SEC"2"
CDS_LOCATION"U25W4"
LOCATION"U25W4"
VALUE"AST2520A1-GP-GP"
CDS_LIB"w_hdl"
CDS_LMAN_SYM_OUTLINE"-1150,1150,1150,-1150"
PART_NUMBER"071.2520A.M001"
PACK_TYPE"ASIC2-GB1";
"GPIOQ5_SDA14"
$PN"N22"47;
"GPIOQ4_SCL14"
$PN"N21"48;
"GPIOB5_LPCPD#_LPCSMI# \B"
$PN"H21"17;
"GPIOK4_SCL7"
$PN"N1"55;
"GPIOK5_SDA7"
$PN"P1"5;
"GPIOK6_SCL8"
$PN"P2"58;
"GPIOK7_SDA8"
$PN"R1"57;
"GPIOA4_TIMER5_SCL9"
$PN"C14"56;
"GPIOA5_TIMER6_SDA9"
$PN"A13"65;
"GPIOI3_SYSMISO"
$PN"C16"63;
"GPIOI2_SYSMOSI"
$PN"B16"66;
"GPIOJ3_SGPMI"
$PN"N4"31;
"GPIOG0_SGPS1CK"
$PN"A19"41;
"GPIOG1_SGPS1LD"
$PN"E19"40;
"GPIOK3_SDA6"
$PN"N2"54;
"GPIOK2_SCL6"
$PN"L1"53;
"GPIOK1_SDA5"
$PN"L4"52;
"GPIOK0_SCL5"
$PN"L3"51;
"GPIOQ3_SDA4"
$PN"B9"64;
"GPIOQ2_SCL4"
$PN"A9"50;
"GPIOQ1_SDA3"
$PN"A10"49;
"GPIOQ0_SCL3"
$PN"A11"9;
"GPIOY7_SDA2"
$PN"P20"10;
"GPIOY6_SCL2"
$PN"M20"13;
"GPIOB7"
$PN"H20"22;
"GPIOB3"
$PN"K18"16;
"GPIOB2"
$PN"L18"12;
"GPIOB1"
$PN"L19"11;
"GPIOB0"
$PN"K19"21;
"TDO"
$PN"D11"46;
"GPIOY5_SDA1"
$PN"M19"15;
"DACB"
$PN"J2"36;
"GPIOG2_SGPS1I0"
$PN"C19"26;
"GPIOG3_SGPS1I1"
$PN"E16"27;
"GPIOJ2_SGPMO"
$PN"N3"25;
"GPIOJ0_SGPMCK"
$PN"R2"30;
"GPIOJ1_SGPMLD"
$PN"L2"38;
"GPIOI6_SPI1MOSI_VBMOSI"
$PN"A14"62;
"GPIOI4_SPI1CS0#_VBCS# \B"
$PN"B15"28;
"GPIOI5_SPI1CK_VBCK"
$PN"C15"61;
"GPIOI0_SYSCS# \B"
$PN"C18"68;
"GPIOI1_SYSCK"
$PN"E15"67;
"NTRST"
$PN"E11"42;
"RTCK"
$PN"C9"35;
"TCK"
$PN"C10"43;
"TDI"
$PN"D12"45;
"TMS"
$PN"C8"44;
"DACG"
$PN"J3"6;
"DACR"
$PN"J4"37;
"DACRSET"
$PN"K4"24;
"GPIOI7_SPI1MISO_VBMISO"
$PN"A15"29;
"GPIOY4_SCL1"
$PN"M18"14;
"GPIOB4_USBCKI"
$PN"J20"19;
"GPIOB6_LPCPME# \B"
$PN"H22"18;
END.
